# S9S_MB_2U (Grand Teton) — schematic netlist excerpt (pin names and nets, part order shuffled) for the footprints in the layout excerpt that follows; sources: Cadence DE-HDL packaged netlist, KiCad conversion of 03242023_DA0F0TMBIJ0_F0T_Motherboard_J_brd_V01_OCP.brd

C442  Q_CAP  22UF 4V 20% X6S  pkg C0402  page 77 : A = PVCCFA_EHV_FIVRA_CPU1 ; B = GND
R3998  Q_RES  0 5% CHIP  pkg 0402LF  page 242 : A = P12V_SCM_EN ; B = P12V_SCM_EN_R2

(kicad_pcb
	(version 20260206)
	(generator "pcbnew")
	(generator_version "10.0")
	(general
		(thickness 1.6)
		(legacy_teardrops no)
	)
	(paper "A4")
	(title_block
		(title "03242023_DA0F0TMBIJ0_F0T_Motherboard_J_brd_V01_OCP.brd")
		(comment 1 "Grand Teton / footprints 1338-1339 of 6105")
	)
	(layers
		(0 "F.Cu" signal "TOP")
		(4 "In1.Cu" signal "GND")
		(6 "In2.Cu" signal "IN1")
		(8 "In3.Cu" signal "GND1")
		(10 "In4.Cu" signal "IN2")
		(12 "In5.Cu" signal "GND2")
		(14 "In6.Cu" signal "IN3")
		(16 "In7.Cu" signal "GND3")
		(18 "In8.Cu" signal "VCC")
		(20 "In9.Cu" signal "VCC1")
		(22 "In10.Cu" signal "GND4")
		(24 "In11.Cu" signal "IN4")
		(26 "In12.Cu" signal "GND5")
		(28 "In13.Cu" signal "IN5")
		(30 "In14.Cu" signal "GND6")
		(32 "In15.Cu" signal "IN6")
		(34 "In16.Cu" signal "GND7")
		(2 "B.Cu" signal "BOTTOM")
		(9 "F.Adhes" user "F.Adhesive")
		(11 "B.Adhes" user "B.Adhesive")
		(13 "F.Paste" user "Package Geometry/Pastemask Top")
		(15 "B.Paste" user "Package Geometry/Pastemask Bottom")
		(5 "F.SilkS" user "Ref Des/Silkscreen Top")
		(7 "B.SilkS" user "Ref Des/Silkscreen Bottom")
		(1 "F.Mask" user "Board Geometry/Soldermask Top")
		(3 "B.Mask" user "Board Geometry/Soldermask Bottom")
		(17 "Dwgs.User" user "User.Drawings")
		(19 "Cmts.User" user "User.Comments")
		(21 "Eco1.User" user "User.Eco1")
		(23 "Eco2.User" user "User.Eco2")
		(25 "Edge.Cuts" user "Board Geometry/Outline")
		(27 "Margin" user)
		(31 "F.CrtYd" user "Package Geometry/Place Bound Top")
		(29 "B.CrtYd" user "Package Geometry/Place Bound Bottom")
		(35 "F.Fab" user "Ref Des/Assembly Top")
		(33 "B.Fab" user "Ref Des/Assembly Bottom")
	)
	(footprint ""
		(layer "F.Cu")
		(at 118.542816 -260.36524 -90)
		(property "Reference" "C442"
			(at 0 0 270)
			(layer "F.SilkS")
			(hide yes)
			(effects
				(font
					(size 1.27 1.27)
				)
			)
		)
		(property "Value" ""
			(at 0 0 270)
			(layer "F.Fab")
			(effects
				(font
					(size 1.27 1.27)
				)
			)
		)
		(duplicate_pad_numbers_are_jumpers no)
		(fp_line
			(start -0.7874 0.4064)
			(end -0.7874 -0.4064)
			(stroke
				(width 0.1524)
				(type default)
			)
			(layer "F.SilkS")
		)
		(fp_line
			(start 0.7874 0.4064)
			(end -0.7874 0.4064)
			(stroke
				(width 0.1524)
				(type default)
			)
			(layer "F.SilkS")
		)
		(fp_line
			(start -0.7874 -0.4064)
			(end 0.7874 -0.4064)
			(stroke
				(width 0.1524)
				(type default)
			)
			(layer "F.SilkS")
		)
		(fp_line
			(start 0.7874 -0.4064)
			(end 0.7874 0.4064)
			(stroke
				(width 0.1524)
				(type default)
			)
			(layer "F.SilkS")
		)
		(fp_line
			(start -0.67945 0.3048)
			(end -0.67945 -0.305054)
			(stroke
				(width 0.1)
				(type default)
			)
			(layer "F.Fab")
		)
		(fp_line
			(start -0.12065 0.3048)
			(end -0.67945 0.3048)
			(stroke
				(width 0.1)
				(type default)
			)
			(layer "F.Fab")
		)
		(fp_line
			(start 0.120396 0.3048)
			(end 0.120396 0.2794)
			(stroke
				(width 0.1)
				(type default)
			)
			(layer "F.Fab")
		)
		(fp_line
			(start 0.67945 0.3048)
			(end 0.120396 0.3048)
			(stroke
				(width 0.1)
				(type default)
			)
			(layer "F.Fab")
		)
		(fp_line
			(start -0.12065 0.2794)
			(end -0.12065 0.3048)
			(stroke
				(width 0.1)
				(type default)
			)
			(layer "F.Fab")
		)
		(fp_line
			(start 0.120396 0.2794)
			(end -0.12065 0.2794)
			(stroke
				(width 0.1)
				(type default)
			)
			(layer "F.Fab")
		)
		(fp_line
			(start -0.12065 -0.2794)
			(end 0.12065 -0.2794)
			(stroke
				(width 0.1)
				(type default)
			)
			(layer "F.Fab")
		)
		(fp_line
			(start 0.12065 -0.2794)
			(end 0.12065 -0.3048)
			(stroke
				(width 0.1)
				(type default)
			)
			(layer "F.Fab")
		)
		(fp_line
			(start 0.12065 -0.3048)
			(end 0.67945 -0.3048)
			(stroke
				(width 0.1)
				(type default)
			)
			(layer "F.Fab")
		)
		(fp_line
			(start 0.67945 -0.3048)
			(end 0.67945 0.3048)
			(stroke
				(width 0.1)
				(type default)
			)
			(layer "F.Fab")
		)
		(fp_line
			(start -0.67945 -0.305054)
			(end -0.12065 -0.305054)
			(stroke
				(width 0.1)
				(type default)
			)
			(layer "F.Fab")
		)
		(fp_line
			(start -0.12065 -0.305054)
			(end -0.12065 -0.2794)
			(stroke
				(width 0.1)
				(type default)
			)
			(layer "F.Fab")
		)
		(pad "1" smd circle
			(at -0.40005 0 270)
			(size 0 0)
			(layers "F.Cu" "F.Mask" "F.Paste")
			(net "PVCCFA_EHV_FIVRA_CPU1")
		)
		(pad "2" smd circle
			(at 0.40005 0 270)
			(size 0 0)
			(layers "F.Cu" "F.Mask" "F.Paste")
			(net "GND")
		)
	)
	(footprint ""
		(layer "F.Cu")
		(at 180.074062 -32.935672 -90)
		(property "Reference" "R3998"
			(at 0 0 270)
			(layer "F.SilkS")
			(hide yes)
			(effects
				(font
					(size 1.27 1.27)
				)
			)
		)
		(property "Value" ""
			(at 0 0 270)
			(layer "F.Fab")
			(effects
				(font
					(size 1.27 1.27)
				)
			)
		)
		(duplicate_pad_numbers_are_jumpers no)
		(fp_line
			(start -0.7874 0.4064)
			(end -0.7874 -0.4064)
			(stroke
				(width 0.1524)
				(type default)
			)
			(layer "F.SilkS")
		)
		(fp_line
			(start 0.7874 0.4064)
			(end -0.7874 0.4064)
			(stroke
				(width 0.1524)
				(type default)
			)
			(layer "F.SilkS")
		)
		(fp_line
			(start -0.7874 -0.4064)
			(end 0.7874 -0.4064)
			(stroke
				(width 0.1524)
				(type default)
			)
			(layer "F.SilkS")
		)
		(fp_line
			(start 0.7874 -0.4064)
			(end 0.7874 0.4064)
			(stroke
				(width 0.1524)
				(type default)
			)
			(layer "F.SilkS")
		)
		(fp_line
			(start -0.67945 0.3048)
			(end -0.67945 -0.305054)
			(stroke
				(width 0.1)
				(type default)
			)
			(layer "F.Fab")
		)
		(fp_line
			(start -0.12065 0.3048)
			(end -0.67945 0.3048)
			(stroke
				(width 0.1)
				(type default)
			)
			(layer "F.Fab")
		)
		(fp_line
			(start 0.120396 0.3048)
			(end 0.120396 0.2794)
			(stroke
				(width 0.1)
				(type default)
			)
			(layer "F.Fab")
		)
		(fp_line
			(start 0.67945 0.3048)
			(end 0.120396 0.3048)
			(stroke
				(width 0.1)
				(type default)
			)
			(layer "F.Fab")
		)
		(fp_line
			(start -0.12065 0.2794)
			(end -0.12065 0.3048)
			(stroke
				(width 0.1)
				(type default)
			)
			(layer "F.Fab")
		)
		(fp_line
			(start 0.120396 0.2794)
			(end -0.12065 0.2794)
			(stroke
				(width 0.1)
				(type default)
			)
			(layer "F.Fab")
		)
		(fp_line
			(start -0.12065 -0.2794)
			(end 0.12065 -0.2794)
			(stroke
				(width 0.1)
				(type default)
			)
			(layer "F.Fab")
		)
		(fp_line
			(start 0.12065 -0.2794)
			(end 0.12065 -0.3048)
			(stroke
				(width 0.1)
				(type default)
			)
			(layer "F.Fab")
		)
		(fp_line
			(start 0.12065 -0.3048)
			(end 0.67945 -0.3048)
			(stroke
				(width 0.1)
				(type default)
			)
			(layer "F.Fab")
		)
		(fp_line
			(start 0.67945 -0.3048)
			(end 0.67945 0.3048)
			(stroke
				(width 0.1)
				(type default)
			)
			(layer "F.Fab")
		)
		(fp_line
			(start -0.67945 -0.305054)
			(end -0.12065 -0.305054)
			(stroke
				(width 0.1)
				(type default)
			)
			(layer "F.Fab")
		)
		(fp_line
			(start -0.12065 -0.305054)
			(end -0.12065 -0.2794)
			(stroke
				(width 0.1)
				(type default)
			)
			(layer "F.Fab")
		)
		(pad "1" smd circle
			(at -0.40005 0 270)
			(size 0 0)
			(layers "F.Cu" "F.Mask" "F.Paste")
			(net "P12V_SCM_EN")
		)
		(pad "2" smd circle
			(at 0.40005 0 270)
			(size 0 0)
			(layers "F.Cu" "F.Mask" "F.Paste")
			(net "P12V_SCM_EN_R2")
		)
	)
)
